FILE_TYPE = CONNECTIVITY;
{Allegro Design Entry HDL 16.6-p007 (v16-6-112F) 10/10/2012}
"PAGE_NUMBER" = 111;
0"NC";
1"GND\g";
2"GND\g";
3"PVCCIO_CPU0\g";
4"GND\g";
5"P3V3_STBY\g";
6"P3V3_STBY\g";
7"P1V05_PCH_STBY\g";
8"GND\g";
9"P1V05_PCH_STBY\g";
10"P1V05_PCH_STBY\g";
11"GND\g";
12"P3V3_STBY\g";
13"GND\g";
14"GND\g";
15"P3V3\g";
16"XDP_RSMRST_N";
17"FM_DEBUG_RST_BTN_N";
18"TP_XDP_CPU_OBSDATA_D1";
19"TP_XDP_CPU_OBSDATA_D2";
20"XDP_PREQ_N";
21"XDP_TDO";
22"XDP_TRST_N";
23"XDP_PRESENT_N";
24"XDP_SPI_PCH_MOSI_BOOT_HALT_N";
25"TP_XDP_CPU_OBSDATA_C1";
26"TP_XDP_CPU_OBSDATA_C0";
27"TP_XDP_CPU_OBSDATA_C2";
28"SPI_PCH_MOSI";
29"TP_XDP_CPU_OBSDATA_C3";
30"XDP_TDI";
31"TP_XDP_OBSDATA_B1";
32"XDP_PCH_TCK1";
33"SMB_HOST_STBY_LVC3_SDA";
34"SMB_HOST_STBY_LVC3_SCL";
35"XDP_SYSPWROK";
36"XDP_CPU_PWR_DEBUG_N";
37"XDP_PWRGD_RST_N";
38"XDP_PRDY_N";
39"TP_XDP_OBSDATA_A1";
40"TP_XDP_OBSDATA_A2";
41"XDP_DEBUG_CONSENT_N";
42"XDP_CPU_GTL_TCK_R2";
43"TP_XDP_CPU_OBSFN_C0";
44"TP_XDP_OBSFN_B0";
45"XDP_OBSFN_B0_MBP6_N";
46"XDP_OBSFN_B1_MBP7_N";
47"TP_XDP_CPU_OBSDATA_D0";
48"TP_XDP_CPU_OBSDATA_D3";
49"CLK_100M_PCH_XDP_DP";
50"CLK_100M_PCH_XDP_DN";
51"XDP_RST_CO_N";
52"XDP_ITP_PMODE";
53"TP_XDP_OBSDATA_B0";
54"TP_XDP_OBSDATA_A3";
55"XDP_PCH_CPU_TCK0";
56"XDP_CPU_TCK_BUF";
57"XDP_ITP_PMODE";
58"XDP_PWRGD_RST_N";
59"XDP_RST_CO_N";
60"XDP_SYSPWROK";
61"TP_XDP_OBSFN_B1";
62"SPI_PCH_IO2";
63"FM_DEBUG_RST_BTN_R1_N";
64"CPU_XDP_PRESENT_N";
65"XDP_CPU_PWR_DEBUG_N";
66"TP_XDP_OBSDATA_B2";
67"TP_XDP_OBSDATA_B3";
68"XDP_CPU_TCK0";
69"RST_RSMRST_N";
70"TP_XDP_OBSDATA_A0";
71"XDP_TMS";
%"CAP_A"
"1","(2750,1900)","1","dev_discrete","I10";
;
PACK_TYPE"0402V"
MATERIAL"X7R"
PART_NUMBER"A36096-030"
VOLTAGE"16V"
TOLERANCE"10%"
LOCATION"C9A2"
VALUE"0.1UF"
SEC_TYPE"0402V"
CDS_LIB"dev_discrete"
CDS_LOCATION"C9A2"
CDS_SEC"1"
ROOM"DEBUG"
BOM_COST"DEBUG"
SEC"1";
"B"
$PN"2"8;
"A"
$PN"1"60;
%"RES"
"1","(2725,1700)","0","mstr_discrete","I11";
;
CDS_SEC"1"
MATERIAL"CHIP"
PACK_TYPE"0402"
LOCATION"R9A14"
VALUE"1.00K"
WATTAGE"1/16W"
TOLERANCE"1%"
PART_NUMBER"G21796-026"
CDS_LOCATION"R9A14"
CDS_LIB"mstr_discrete"
SEC"1"
BOM_COST"DEBUG"
SEC_TYPE"0402"
ROOM"DEBUG";
"B"
$PN"2"5;
"A"
$PN"1"59;
%"CAP_A"
"1","(2800,1450)","1","dev_discrete","I12";
;
VOLTAGE"16V"
MATERIAL"X7R"
VALUE"0.1UF"
PART_NUMBER"A36096-030"
TOLERANCE"10%"
LOCATION"C9A5"
PACK_TYPE"0402V"
CDS_LIB"dev_discrete"
CDS_LOCATION"C9A5"
SEC"1"
SEC_TYPE"0402V"
CDS_SEC"1"
BOM_COST"DEBUG"
ROOM"DEBUG";
"B"
$PN"2"11;
"A"
$PN"1"59;
%"RES"
"1","(2725,1150)","0","mstr_discrete","I13";
;
CDS_SEC"1"
MATERIAL"CHIP"
TOLERANCE"1%"
WATTAGE"1/16W"
VALUE"1.00K"
LOCATION"R1L23"
PACK_TYPE"0402"
PART_NUMBER"G21796-026"
SEC"1"
SEC_TYPE"0402"
BOM_COST"DEBUG"
ROOM"DEBUG"
CDS_LOCATION"R1L23"
CDS_LIB"mstr_discrete";
"B"
$PN"2"5;
"A"
$PN"1"58;
%"CAP_A"
"1","(2825,950)","1","dev_discrete","I14";
;
PACK_TYPE"0402V"
MATERIAL"X7R"
VALUE"0.1UF"
VOLTAGE"16V"
PART_NUMBER"A36096-030"
TOLERANCE"10%"
LOCATION"C1L8"
SEC"1"
BOM_COST"DEBUG"
ROOM"DEBUG"
SEC_TYPE"0402V"
CDS_SEC"1"
CDS_LOCATION"C1L8"
CDS_LIB"dev_discrete";
"B"
$PN"2"14;
"A"
$PN"1"58;
%"GND"
"1","(875,2625)","0","mstr_symbols","I24";
;
ROOM"CPU_XDP_DEBUG"
BOM_COST"DEBUG"
VOLTAGE"0.0V"
CDS_LIB"mstr_symbols"
SIZE"1B"
BODY_TYPE"PLUMBING"
HDL_POWER"GND";
"A\NAC"1;
%"CAP_A"
"1","(750,2925)","2","dev_discrete","I25";
;
PART_NUMBER"D97712-004"
PACK_TYPE"0402V"
MATERIAL"X6S"
VOLTAGE"6.3V"
TOLERANCE"10%"
VALUE"1.0UF"
LOCATION"C9A6"
CDS_LIB"dev_discrete"
BOM_COST"DEBUG"
CDS_LOCATION"C9A6"
ROOM"DEBUG"
$SEC"1"
CDS_SEC"1";
"B"
$PN"2"1;
"A"
$PN"1"9;
%"SCONN60_C21100002"
"1","(350,3950)","0","mstr_sconn","I26";
;
CDS_SEC"1"
PART_NUMBER"C21100-002"
LOCATION"J9A3"
PACK_TYPE"SMLF"
MATERIAL"CONN"
CDS_LIB"mstr_sconn"
ALLOW_CONNECT"TRUE"
CDS_LOCATION"J9A3"
ROOM"DEBUG"
BOM_COST"DEBUG"
SEC_TYPE"SMLF"
SEC"1";
"IO11 \B"
$PN"11"39;
"IO9 \B"
$PN"9"70;
"IO3 \B"
$PN"3"20;
"IO1 \B"
$PN"1"41;
"IO59 \B"
$PN"59"2;
"IO55 \B"
$PN"55"32;
"IO57 \B"
$PN"57"68;
"IO51 \B"
$PN"51"33;
"IO53 \B"
$PN"53"34;
"IO49 \B"
$PN"49"2;
"IO45 \B"
$PN"45"36;
"IO47 \B"
$PN"47"35;
"IO39 \B"
$PN"39"16;
"IO41 \B"
$PN"41"37;
"IO43 \B"
$PN"43"10;
"IO37 \B"
$PN"37"2;
"IO35 \B"
$PN"35"67;
"IO29 \B"
$PN"29"31;
"IO31 \B"
$PN"31"2;
"IO33 \B"
$PN"33"66;
"IO25 \B"
$PN"25"2;
"IO27 \B"
$PN"27"53;
"IO23 \B"
$PN"23"61;
"IO19 \B"
$PN"19"2;
"IO21 \B"
$PN"21"44;
"IO15 \B"
$PN"15"40;
"IO17 \B"
$PN"17"54;
"IO13 \B"
$PN"13"2;
"IO5 \B"
$PN"5"38;
"IO7 \B"
$PN"7"2;
"IO60 \B"
$PN"60"23;
"IO56 \B"
$PN"56"30;
"IO58 \B"
$PN"58"71;
"IO52 \B"
$PN"52"21;
"IO54 \B"
$PN"54"22;
"IO50 \B"
$PN"50"1;
"IO46 \B"
$PN"46"52;
"IO48 \B"
$PN"48"51;
"IO40 \B"
$PN"40"49;
"IO42 \B"
$PN"42"50;
"IO44 \B"
$PN"44"9;
"IO38 \B"
$PN"38"1;
"IO36 \B"
$PN"36"48;
"IO30 \B"
$PN"30"18;
"IO32 \B"
$PN"32"1;
"IO34 \B"
$PN"34"19;
"IO26 \B"
$PN"26"1;
"IO28 \B"
$PN"28"47;
"IO24 \B"
$PN"24"46;
"IO20 \B"
$PN"20"1;
"IO22 \B"
$PN"22"45;
"IO16 \B"
$PN"16"27;
"IO18 \B"
$PN"18"29;
"IO14 \B"
$PN"14"1;
"IO10 \B"
$PN"10"26;
"IO12 \B"
$PN"12"25;
"IO2 \B"
$PN"2"1;
"IO6 \B"
$PN"6"24;
"IO8 \B"
$PN"8"1;
"IO4 \B"
$PN"4"43;
%"CAP_A"
"1","(0,2925)","0","dev_discrete","I30";
;
PACK_TYPE"0402V"
MATERIAL"X6S"
PART_NUMBER"D97712-004"
TOLERANCE"10%"
VOLTAGE"6.3V"
LOCATION"C1L5"
VALUE"1.0UF"
CDS_LIB"dev_discrete"
CDS_LOCATION"C1L5"
BOM_COST"DEBUG"
ROOM"DEBUG"
CDS_SEC"1"
$SEC"1";
"B"
$PN"2"2;
"A"
$PN"1"10;
%"RES"
"1","(-2100,4650)","0","mstr_discrete","I37";
;
CDS_SEC"1"
WATTAGE"1/16W"
LOCATION"R2P2"
TOLERANCE"1%"
VALUE"1.00K"
PART_NUMBER"G21796-026"
PACK_TYPE"0402"
MATERIAL"CHIP"
CDS_LOCATION"R2P2"
BOM_COST"DEBUG"
SEC_TYPE"0402"
CDS_LIB"mstr_discrete"
SEC"1"
ROOM"DEBUG";
"B"
$PN"2"41;
"A"
$PN"1"62;
%"GND"
"1","(-100,2625)","0","mstr_symbols","I39";
;
ROOM"CPU_XDP_DEBUG"
BOM_COST"DEBUG"
VOLTAGE"0.0V"
SIZE"1B"
CDS_LIB"mstr_symbols"
BODY_TYPE"PLUMBING"
HDL_POWER"GND";
"A\NAC"2;
%"PVCCIO_CPU0"
"1","(-850,1600)","0","mstr_symbols","I54";
;
CDS_LIB"mstr_symbols"
VOLTAGE"1.1V"
BODY_TYPE"PLUMBING"
HDL_POWER"PVCCIO_CPU0";
"G\NAC"3;
%"RES"
"1","(-1400,1450)","0","mstr_discrete","I55";
;
CDS_SEC"1"
PACK_TYPE"0402"
LOCATION"R9A4"
MATERIAL"CHIP"
PART_NUMBER"G21796-077"
TOLERANCE"1%"
WATTAGE"1/16W"
VALUE"475.0"
CDS_LOCATION"R9A4"
CDS_LIB"mstr_discrete"
BOM_COST"DEBUG"
SEC_TYPE"0402"
ROOM"DEBUG"
SEC"1";
"B"
$PN"2"3;
"A"
$PN"1"64;
%"RES"
"1","(-1400,1100)","0","mstr_discrete","I56";
;
CDS_SEC"1"
WATTAGE"1/16W"
TOLERANCE"1%"
MATERIAL"CHIP"
LOCATION"R1L17"
PART_NUMBER"G21796-009"
PACK_TYPE"0402"
VALUE"150.0"
SEC"1"
ROOM"DEBUG"
CDS_LIB"mstr_discrete"
BOM_COST"DEBUG"
SEC_TYPE"0402"
CDS_LOCATION"R1L17";
"B"
$PN"2"3;
"A"
$PN"1"65;
%"RES"
"1","(-1400,500)","0","mstr_discrete","I57";
;
CDS_SEC"1"
TOLERANCE"1%"
LOCATION"R9A17"
WATTAGE"1/16W"
VALUE"1.00K"
MATERIAL"CHIP"
PACK_TYPE"0402"
PART_NUMBER"G21796-026"
CDS_LIB"mstr_discrete"
ROOM"DEBUG"
BOM_COST"DEBUG"
SEC_TYPE"0402"
CDS_LOCATION"R9A17"
SEC"1";
"B"
$PN"2"7;
"A"
$PN"1"57;
%"GND"
"1","(-1100,800)","0","mstr_symbols","I58";
;
CDS_LIB"mstr_symbols"
VOLTAGE"0.0V"
SIZE"1B"
BOM_COST"DEBUG"
ROOM"CPU_XDP_DEBUG"
BODY_TYPE"PLUMBING"
HDL_POWER"GND";
"A\NAC"4;
%"CAP_A"
"1","(-1400,875)","1","dev_discrete","I59";
;
PACK_TYPE"0402V"
MATERIAL"X7R"
VALUE"0.1UF"
LOCATION"C9A4"
VOLTAGE"16V"
TOLERANCE"10%"
PART_NUMBER"A36096-030"
SEC"1"
BOM_COST"DEBUG"
ROOM"DEBUG"
CDS_SEC"1"
CDS_LIB"dev_discrete"
CDS_LOCATION"C9A4"
SEC_TYPE"0402V";
"B"
$PN"2"4;
"A"
$PN"1"65;
%"RES"
"1","(2725,2150)","0","mstr_discrete","I6";
;
CDS_SEC"1"
PART_NUMBER"G21796-026"
TOLERANCE"1%"
LOCATION"R1L13"
PACK_TYPE"0402"
MATERIAL"CHIP"
WATTAGE"1/16W"
VALUE"1.00K"
CDS_LIB"mstr_discrete"
CDS_LOCATION"R1L13"
BOM_COST"DEBUG"
SEC_TYPE"0402"
ROOM"DEBUG"
SEC"1";
"B"
$PN"2"5;
"A"
$PN"1"60;
%"RES"
"1","(-2175,3700)","0","mstr_discrete","I60";
;
CDS_SEC"1"
PACK_TYPE"0402"
MATERIAL"CHIP"
LOCATION"R9A15"
PART_NUMBER"G21796-026"
WATTAGE"1/16W"
TOLERANCE"1%"
VALUE"1.00K"
CDS_LOCATION"R9A15"
CDS_LIB"mstr_discrete"
SEC_TYPE"0402"
BOM_COST"DEBUG"
SEC"1"
ROOM"DEBUG";
"B"
$PN"2"16;
"A"
$PN"1"69;
%"P3V3_STBY"
"1","(3250,2300)","0","mstr_symbols","I65";
;
VOLTAGE"3.3V"
CDS_LIB"mstr_symbols"
SIZE"1B"
BODY_TYPE"PLUMBING"
HDL_POWER"P3V3_STBY";
"G\NAC"5;
%"P3V3_STBY"
"1","(2175,2975)","0","mstr_symbols","I67";
;
CDS_LIB"mstr_symbols"
VOLTAGE"3.3V"
SIZE"1B"
BODY_TYPE"PLUMBING"
HDL_POWER"P3V3_STBY";
"G\NAC"6;
%"RES"
"1","(2950,2600)","0","mstr_discrete","I68";
;
CDS_SEC"1"
PACK_TYPE"0402"
PART_NUMBER"G21796-074"
MATERIAL"CHIP"
WATTAGE"1/16W"
TOLERANCE"1%"
VALUE"33.2"
LOCATION"R1L29"
CDS_LOCATION"R1L29"
CDS_LIB"mstr_discrete"
SEC"1"
SEC_TYPE"0402"
ROOM"M-SATA";
"B"
$PN"2"17;
"A"
$PN"1"63;
%"P1V05_PCH_STBY"
"1","(-850,650)","0","mstr_symbols","I69";
;
CDS_LIB"mstr_symbols"
VOLTAGE"1.05V"
BODY_TYPE"PLUMBING"
HDL_POWER"P1V05_PCH_STBY";
"G\NAC"7;
%"GND"
"1","(3075,1825)","0","mstr_symbols","I7";
;
ROOM"CPU_XDP_DEBUG"
VOLTAGE"0.0V"
BOM_COST"DEBUG"
SIZE"1B"
CDS_LIB"mstr_symbols"
BODY_TYPE"PLUMBING"
HDL_POWER"GND";
"A\NAC"8;
%"P1V05_PCH_STBY"
"1","(750,4750)","0","mstr_symbols","I70";
;
CDS_LIB"mstr_symbols"
VOLTAGE"1.05V"
BODY_TYPE"PLUMBING"
HDL_POWER"P1V05_PCH_STBY";
"G\NAC"9;
%"P1V05_PCH_STBY"
"1","(0,4750)","0","mstr_symbols","I71";
;
VOLTAGE"1.05V"
CDS_LIB"mstr_symbols"
BODY_TYPE"PLUMBING"
HDL_POWER"P1V05_PCH_STBY";
"G\NAC"10;
%"RES"
"1","(-1900,3100)","0","mstr_discrete","I74";
;
CDS_SEC"1"
PART_NUMBER"G21497-005"
MATERIAL"CHIP"
WATTAGE"1/16W"
VALUE"0.0"
TOLERANCE"5%"
LOCATION"R9A3"
PACK_TYPE"0402"
ROOM"DEBUG"
SEC"1"
SEC_TYPE"0402"
CDS_LIB"mstr_discrete"
CDS_LOCATION"R9A3";
"B"
$PN"2"68;
"A"
$PN"1"55;
%"GND"
"1","(3100,1375)","0","mstr_symbols","I8";
;
ROOM"CPU_XDP_DEBUG"
VOLTAGE"0.0V"
BOM_COST"DEBUG"
CDS_LIB"mstr_symbols"
SIZE"1B"
BODY_TYPE"PLUMBING"
HDL_POWER"GND";
"A\NAC"11;
%"RES"
"2","(-2925,2675)","0","mstr_discrete","I83";
;
CDS_SEC"1"
LOCATION"R9A2"
VALUE"33.2"
TOLERANCE"1%"
WATTAGE"1/16W"
MATERIAL"EMPTY"
PART_NUMBER"G21796-074"
PACK_TYPE"0402"
CDS_LIB"mstr_discrete"
CDS_LOCATION"R9A2"
ROOM"DEBUG"
SEC_TYPE"0402"
SEC"1";
"A"
$PN"1"55;
"B"
$PN"2"42;
%"TTL1G07_A"
"1","(1775,2600)","0","mstr_ttl","I85";
;
CDS_SEC"1"
LOCATION"U1L4"
MATERIAL"IC"
VALUE"74LVC1G07"
PART_NUMBER"C88419-001"
POWER_GROUP"VCC=P3V3_STBY;GND=GND"
ROOM"M-SATA"
BOM_COST"M-SATA"
SEC_TYPE"SOP"
SEC"1"
CDS_LOCATION"U1L4"
CDS_LIB"mstr_ttl"
PACK_TYPE"SOP";
"Y"
$PN"4"63;
"A"
$PN"2"51;
%"P3V3_STBY"
"1","(3900,3925)","0","mstr_symbols","I86";
;
VOLTAGE"3.3V"
CDS_LIB"mstr_symbols"
SIZE"1B"
BODY_TYPE"PLUMBING"
HDL_POWER"P3V3_STBY";
"G\NAC"12;
%"CAP_A"
"1","(3900,3625)","0","dev_discrete","I87";
;
MATERIAL"X7R"
PACK_TYPE"0402V"
TOLERANCE"10%"
LOCATION"C1L11"
VOLTAGE"16V"
VALUE"0.1UF"
PART_NUMBER"A36096-030"
ROOM"DEBUG"
CDS_LIB"dev_discrete"
CDS_SEC"1"
CDS_LOCATION"C1L11"
SEC"1"
SEC_TYPE"0402V"
BOM_COST"DEBUG";
"B"
$PN"2"13;
"A"
$PN"1"12;
%"GND"
"1","(3900,3325)","0","mstr_symbols","I88";
;
VOLTAGE"0.0V"
SIZE"1B"
CDS_LIB"mstr_symbols"
BODY_TYPE"PLUMBING"
HDL_POWER"GND";
"A\NAC"13;
%"RES"
"1","(2050,4550)","0","mstr_discrete","I89";
;
CDS_SEC"1"
PACK_TYPE"0402"
PART_NUMBER"G21796-026"
LOCATION"R8E2"
VALUE"1.00K"
WATTAGE"1/16W"
MATERIAL"CHIP"
TOLERANCE"1%"
CDS_LOCATION"R8E2"
ROOM"DEBUG"
BOM_COST"DEBUG"
SEC_TYPE"0402"
SEC"1"
CDS_LIB"mstr_discrete";
"B"
$PN"2"28;
"A"
$PN"1"24;
%"GND"
"1","(3125,875)","0","mstr_symbols","I9";
;
SIZE"1B"
VOLTAGE"0.0V"
CDS_LIB"mstr_symbols"
BOM_COST"DEBUG"
ROOM"CPU_XDP_DEBUG"
BODY_TYPE"PLUMBING"
HDL_POWER"GND";
"A\NAC"14;
%"NPN_DUAL"
"2","(-2150,2325)","0","mstr_discrete","I93";
;
CDS_SEC"2"
PART_NUMBER"C52264-001"
LOCATION"Q9A1"
VALUE"MBT3904"
MATERIAL"EMPTY"
ROOM"DEBUG"
SEC"2"
SEC_TYPE"SSOPLF"
PACK_TYPE"SSOPLF"
CDS_LIB"mstr_discrete"
CDS_LOCATION"Q9A1";
"B <SIZE-1..0>"
$PN"2"56;
"E <SIZE-1..0>"
$PN"1"42;
"C <SIZE-1..0>"
$PN"6"56;
%"NPN_DUAL"
"1","(-1150,2275)","0","mstr_discrete","I94";
;
CDS_SEC"1"
LOCATION"Q9A1"
VALUE"MBT3904"
PART_NUMBER"C52264-001"
MATERIAL"EMPTY"
CDS_LIB"mstr_discrete"
CDS_LOCATION"Q9A1"
PACK_TYPE"SSOPLF"
SEC"1"
SEC_TYPE"SSOPLF"
ROOM"DEBUG";
"C <SIZE-1..0>"
$PN"3"15;
"B <SIZE-1..0>"
$PN"5"56;
"E <SIZE-1..0>"
$PN"4"68;
%"RES"
"2","(-1850,2700)","2","mstr_discrete","I95";
;
CDS_SEC"1"
VALUE"1.00K"
LOCATION"R9A1"
MATERIAL"EMPTY"
TOLERANCE"1%"
WATTAGE"1/16W"
PART_NUMBER"G21796-026"
PACK_TYPE"0402"
CDS_LIB"mstr_discrete"
ROOM"DEBUG"
SEC"1"
SEC_TYPE"0402"
CDS_LOCATION"R9A1";
"A"
$PN"1"15;
"B"
$PN"2"56;
%"P3V3"
"1","(-1850,2950)","0","mstr_symbols","I96";
;
VOLTAGE"3.3V"
CDS_LIB"mstr_symbols"
SIZE"1B"
BODY_TYPE"PLUMBING"
HDL_POWER"P3V3";
"G\NAC"15;
%"RES"
"2","(2175,2800)","0","mstr_discrete","I97";
;
CDS_SEC"1"
CDS_LOCATION"R1L28"
PACK_TYPE"0402"
MATERIAL"EMPTY"
TOLERANCE"1%"
WATTAGE"1/16W"
VALUE"4.75K"
LOCATION"R1L28"
PART_NUMBER"G21796-072"
SEC_TYPE"0402"
SEC"1"
CDS_LIB"mstr_discrete"
ROOM"MIO_CHASSIS"
BOM_COST"MIO_CHASSIS";
"A"
$PN"1"6;
"B"
$PN"2"63;
END.
